(kicad_pcb
	(version 20221018)
	(generator pcbnew)
	(general
    (thickness 1.6)
  )
	(paper "A4")
	(title_block
    (title "NUC Computer Cluster Power Breakout HW")
    (date "2023-10-18")
    (rev "1.4.3")
    (company "Antmicro Ltd.")
		(comment 9 "footprints 78-84 of 234")
	)
	(layers
    (0 "F.Cu" mixed)
    (1 "In1.Cu" power)
    (2 "In2.Cu" mixed)
    (31 "B.Cu" power)
    (32 "B.Adhes" user "B.Adhesive")
    (33 "F.Adhes" user "F.Adhesive")
    (34 "B.Paste" user)
    (35 "F.Paste" user)
    (36 "B.SilkS" user "B.Silkscreen")
    (37 "F.SilkS" user "F.Silkscreen")
    (38 "B.Mask" user)
    (39 "F.Mask" user)
    (40 "Dwgs.User" user "User.Drawings")
    (41 "Cmts.User" user "User.Comments")
    (42 "Eco1.User" user "User.Eco1")
    (43 "Eco2.User" user "User.Eco2")
    (44 "Edge.Cuts" user)
    (45 "Margin" user)
    (46 "B.CrtYd" user "B.Courtyard")
    (47 "F.CrtYd" user "F.Courtyard")
    (48 "B.Fab" user)
    (49 "F.Fab" user)
  )
	(footprint "antmicro-footprints:SOT-23-3" (layer "F.Cu")
    (at 101 134.6 180)
    (property "Author" "Antmicro")
    (property "License" "Apache-2.0")
    (property "MPN" "BC856,215")
    (property "Manufacturer" "Nexperia")
    (property "Sheetfile" "d1600e-psu-breakout-board.kicad_sch")
    (property "Sheetname" "")
    (property "ki_description" "Bipolar (BJT) Single Transistor, PNP, 65 V, 100 mA, 250 mW, SOT-23-3, Surface Mount")
    (property "ki_keywords" "SMT, TRANSISTOR, SEMICONDUCTOR, PNP")
    (attr smd)
    (fp_text reference "Q11" (at 1.05 2.15 180) (layer "F.SilkS")
        (effects (font (size 0.7 0.7) (thickness 0.15)) (justify left bottom))
    )
    (fp_text value "BC856,215" (at -1.9 2.7 180) (layer "F.Fab")
        (effects (font (size 0.7 0.7) (thickness 0.15)) (justify left bottom))
    )
    (fp_text user "License: Apache-2.0" (at -1.8 6.8 180) (layer "F.Fab") hide
        (effects (font (size 0.7 0.7) (thickness 0.15)) (justify left bottom))
    )
    (fp_text user "Author: Antmicro" (at -1.837 5.3 180) (layer "F.Fab") hide
        (effects (font (size 0.7 0.7) (thickness 0.15)) (justify left bottom))
    )
    (fp_text user "${REFERENCE}" (at -1.837 4 180) (layer "F.Fab") hide
        (effects (font (size 0.7 0.7) (thickness 0.15)) (justify left bottom))
    )
    (fp_line (start -1.45 -1.35) (end -0.85 -1.35)
      (stroke (width 0.15) (type solid)) (layer "F.SilkS"))
    (fp_line (start -0.85 -1.35) (end -0.7 -1.5)
      (stroke (width 0.15) (type solid)) (layer "F.SilkS"))
    (fp_line (start -0.7 1.5) (end -0.7 1.35)
      (stroke (width 0.15) (type solid)) (layer "F.SilkS"))
    (fp_line (start 0.7 -1.5) (end -0.7 -1.5)
      (stroke (width 0.15) (type solid)) (layer "F.SilkS"))
    (fp_line (start 0.7 -0.4) (end 0.7 -1.5)
      (stroke (width 0.15) (type solid)) (layer "F.SilkS"))
    (fp_line (start 0.7 0.4) (end 0.7 1.5)
      (stroke (width 0.15) (type solid)) (layer "F.SilkS"))
    (fp_line (start 0.7 1.5) (end -0.7 1.5)
      (stroke (width 0.15) (type solid)) (layer "F.SilkS"))
    (fp_line (start -1.75 -0.5) (end -1.75 -1.4)
      (stroke (width 0.05) (type solid)) (layer "F.CrtYd"))
    (fp_line (start -1.75 0.5) (end -0.85 0.5)
      (stroke (width 0.05) (type solid)) (layer "F.CrtYd"))
    (fp_line (start -1.75 1.4) (end -1.75 0.5)
      (stroke (width 0.05) (type solid)) (layer "F.CrtYd"))
    (fp_line (start -0.9 -1.6) (end -0.9 -1.4)
      (stroke (width 0.05) (type solid)) (layer "F.CrtYd"))
    (fp_line (start -0.9 -1.6) (end 0.825 -1.6)
      (stroke (width 0.05) (type solid)) (layer "F.CrtYd"))
    (fp_line (start -0.9 -1.4) (end -1.75 -1.4)
      (stroke (width 0.05) (type solid)) (layer "F.CrtYd"))
    (fp_line (start -0.85 -0.5) (end -1.75 -0.5)
      (stroke (width 0.05) (type solid)) (layer "F.CrtYd"))
    (fp_line (start -0.85 0.5) (end -0.85 -0.5)
      (stroke (width 0.05) (type solid)) (layer "F.CrtYd"))
    (fp_line (start -0.85 1.4) (end -1.75 1.4)
      (stroke (width 0.05) (type solid)) (layer "F.CrtYd"))
    (fp_line (start -0.85 1.65) (end -0.85 1.4)
      (stroke (width 0.05) (type solid)) (layer "F.CrtYd"))
    (fp_line (start 0.825 -1.6) (end 0.825 -0.45)
      (stroke (width 0.05) (type solid)) (layer "F.CrtYd"))
    (fp_line (start 0.825 -0.45) (end 1.75 -0.45)
      (stroke (width 0.05) (type solid)) (layer "F.CrtYd"))
    (fp_line (start 0.85 0.45) (end 0.85 1.65)
      (stroke (width 0.05) (type solid)) (layer "F.CrtYd"))
    (fp_line (start 0.85 1.65) (end -0.85 1.65)
      (stroke (width 0.05) (type solid)) (layer "F.CrtYd"))
    (fp_line (start 1.75 -0.45) (end 1.75 0.45)
      (stroke (width 0.05) (type solid)) (layer "F.CrtYd"))
    (fp_line (start 1.75 0.45) (end 0.85 0.45)
      (stroke (width 0.05) (type solid)) (layer "F.CrtYd"))
    (fp_line (start -0.712 -1.325) (end -0.712 1.523)
      (stroke (width 0.15) (type solid)) (layer "F.Fab"))
    (fp_line (start -0.712 1.519) (end 0.688 1.519)
      (stroke (width 0.15) (type solid)) (layer "F.Fab"))
    (fp_line (start -0.437 -1.526) (end -0.712 -1.325)
      (stroke (width 0.15) (type solid)) (layer "F.Fab"))
    (fp_line (start -0.437 -1.526) (end 0.688 -1.526)
      (stroke (width 0.15) (type solid)) (layer "F.Fab"))
    (fp_line (start 0.688 1.519) (end 0.688 -1.52)
      (stroke (width 0.15) (type solid)) (layer "F.Fab"))
    (pad "1" smd roundrect (at -1.1 -0.951 180) (size 1 0.6) (layers "F.Cu" "F.Paste" "F.Mask") (roundrect_rratio 0.15)
      (net 54 "Net-(Q11-Pad1)") (pintype "input"))
    (pad "2" smd roundrect (at -1.1 0.949 180) (size 1 0.6) (layers "F.Cu" "F.Paste" "F.Mask") (roundrect_rratio 0.15)
      (net 1 "VCC3V3") (pintype "passive"))
    (pad "3" smd roundrect (at 1.1 -0.0005 180) (size 1 0.6) (layers "F.Cu" "F.Paste" "F.Mask") (roundrect_rratio 0.15)
      (net 39 "Net-(D5-A)") (pintype "passive"))
  )
	(footprint "antmicro-footprints:MP_Pad6mm_Drill3.2mm" (layer "F.Cu")
    (at 94 145)
    (property "Author" "Antmicro")
    (property "License" "Apache-2.0")
    (property "Sheetfile" "d1600e-psu-breakout-board.kicad_sch")
    (property "Sheetname" "")
    (property "exclude_from_bom" "")
    (property "ki_description" "Mechanical part")
    (property "ki_keywords" "MECHANICAL")
    (attr exclude_from_pos_files exclude_from_bom)
    (fp_text reference "MP2" (at 0 -3.2) (layer "F.SilkS") hide
        (effects (font (size 0.7 0.7) (thickness 0.15)) (justify left bottom))
    )
    (fp_text value "MP_Pad6mm_Drill3.2mm" (at 0 3.9) (layer "F.Fab")
        (effects (font (size 0.7 0.7) (thickness 0.15)) (justify left bottom))
    )
    (fp_text user "Author: Antmicro" (at -0.178 7.225) (layer "F.Fab") hide
        (effects (font (size 0.7 0.7) (thickness 0.15)) (justify left bottom))
    )
    (fp_text user "License: Apache-2.0" (at -0.178 8.425) (layer "F.Fab") hide
        (effects (font (size 0.7 0.7) (thickness 0.15)) (justify left bottom))
    )
    (fp_text user "${REFERENCE}" (at -0.178 6.025) (layer "F.Fab") hide
        (effects (font (size 0.7 0.7) (thickness 0.15)) (justify left bottom))
    )
    (fp_circle (center 0 0) (end 3.25 0)
      (stroke (width 0.05) (type default)) (fill none) (layer "F.CrtYd"))
    (pad "1" thru_hole circle (at 0 0) (size 6 6) (drill 3.2) (layers "*.Cu" "*.Mask")
      (net 4 "GND") (pintype "passive"))
  )
	(footprint "antmicro-footprints:MP_Pad6mm_Drill3.2mm" (layer "F.Cu")
    (at 186.55 53.9)
    (property "Author" "Antmicro")
    (property "License" "Apache-2.0")
    (property "Sheetfile" "d1600e-psu-breakout-board.kicad_sch")
    (property "Sheetname" "")
    (property "exclude_from_bom" "")
    (property "ki_description" "Mechanical part")
    (property "ki_keywords" "MECHANICAL")
    (attr exclude_from_pos_files exclude_from_bom)
    (fp_text reference "MP3" (at 0 -3.2) (layer "F.SilkS") hide
        (effects (font (size 0.7 0.7) (thickness 0.15)) (justify left bottom))
    )
    (fp_text value "MP_Pad6mm_Drill3.2mm" (at 0 3.9) (layer "F.Fab")
        (effects (font (size 0.7 0.7) (thickness 0.15)) (justify left bottom))
    )
    (fp_text user "${REFERENCE}" (at -0.178 6.025) (layer "F.Fab") hide
        (effects (font (size 0.7 0.7) (thickness 0.15)) (justify left bottom))
    )
    (fp_text user "Author: Antmicro" (at -0.178 7.225) (layer "F.Fab") hide
        (effects (font (size 0.7 0.7) (thickness 0.15)) (justify left bottom))
    )
    (fp_text user "License: Apache-2.0" (at -0.178 8.425) (layer "F.Fab") hide
        (effects (font (size 0.7 0.7) (thickness 0.15)) (justify left bottom))
    )
    (fp_circle (center 0 0) (end 3.25 0)
      (stroke (width 0.05) (type default)) (fill none) (layer "F.CrtYd"))
    (pad "1" thru_hole circle (at 0 0) (size 6 6) (drill 3.2) (layers "*.Cu" "*.Mask")
      (net 4 "GND") (pintype "passive"))
  )
	(footprint "antmicro-footprints:MP_Pad6mm_Drill3.2mm" (layer "F.Cu")
    (at 185 145)
    (property "Author" "Antmicro")
    (property "License" "Apache-2.0")
    (property "Sheetfile" "d1600e-psu-breakout-board.kicad_sch")
    (property "Sheetname" "")
    (property "exclude_from_bom" "")
    (property "ki_description" "Mechanical part")
    (property "ki_keywords" "MECHANICAL")
    (attr exclude_from_pos_files exclude_from_bom)
    (fp_text reference "MP4" (at 0 -3.2) (layer "F.SilkS") hide
        (effects (font (size 0.7 0.7) (thickness 0.15)) (justify left bottom))
    )
    (fp_text value "MP_Pad6mm_Drill3.2mm" (at 0 3.9) (layer "F.Fab")
        (effects (font (size 0.7 0.7) (thickness 0.15)) (justify left bottom))
    )
    (fp_text user "${REFERENCE}" (at -0.178 6.025) (layer "F.Fab") hide
        (effects (font (size 0.7 0.7) (thickness 0.15)) (justify left bottom))
    )
    (fp_text user "License: Apache-2.0" (at -0.178 8.425) (layer "F.Fab") hide
        (effects (font (size 0.7 0.7) (thickness 0.15)) (justify left bottom))
    )
    (fp_text user "Author: Antmicro" (at -0.178 7.225) (layer "F.Fab") hide
        (effects (font (size 0.7 0.7) (thickness 0.15)) (justify left bottom))
    )
    (fp_circle (center 0 0) (end 3.25 0)
      (stroke (width 0.05) (type default)) (fill none) (layer "F.CrtYd"))
    (pad "1" thru_hole circle (at 0 0) (size 6 6) (drill 3.2) (layers "*.Cu" "*.Mask")
      (net 4 "GND") (pintype "passive"))
  )
	(footprint "antmicro-footprints:MOLEX_39288080" (layer "F.Cu")
    (at 111.25 74.7 90)
    (property "Author" "Antmicro")
    (property "License" "Apache-2.0")
    (property "MPN" "39-28-8080")
    (property "Manufacturer" "Molex")
    (property "Sheetfile" "d1600e-psu-breakout-board.kicad_sch")
    (property "Sheetname" "")
    (property "ki_description" "Pin Header, THT, Vertical, UL94V-2, Power, Wire-to-Board, 4.2 mm, 2 Rows, 8 Contacts, Mini-fit Jr, 5566 series")
    (property "ki_keywords" "VERTICAL, THT, HEADER, CONNECTOR, MALE, WIRE-BOARD, POWER")
    (attr through_hole)
    (fp_text reference "J4" (at -2.5 -2.65 90) (layer "F.SilkS")
        (effects (font (size 0.7 0.7) (thickness 0.15)) (justify left bottom))
    )
    (fp_text value "Molex_Mini-Fit-Jr_2x4_39-28-8080" (at 4.49 11.365 90) (layer "F.Fab")
        (effects (font (size 0.7 0.7) (thickness 0.15)) (justify left bottom))
    )
    (fp_text user "Author: Antmicro" (at -3.5 16.965 90) (layer "F.Fab") hide
        (effects (font (size 0.7 0.7) (thickness 0.15)) (justify left bottom))
    )
    (fp_text user "License: Apache-2.0" (at -3.5 14.565 90) (layer "F.Fab") hide
        (effects (font (size 0.7 0.7) (thickness 0.15)) (justify left bottom))
    )
    (fp_text user "${REFERENCE}" (at -3.5 15.765 90) (layer "F.Fab") hide
        (effects (font (size 0.7 0.7) (thickness 0.15)) (justify left bottom))
    )
    (fp_text user "PTH D1.40 +/- 0.05" (at -3.5 13.365 90) (layer "F.Fab") hide
        (effects (font (size 0.7 0.7) (thickness 0.15)) (justify left bottom))
    )
    (fp_line (start -3.1 8.75) (end -3.1 -0.98)
      (stroke (width 0.15) (type solid)) (layer "F.SilkS"))
    (fp_line (start -1.83 -2.25) (end -3.1 -0.98)
      (stroke (width 0.15) (type solid)) (layer "F.SilkS"))
    (fp_line (start -1.83 -2.25) (end 15.7 -2.25)
      (stroke (width 0.15) (type solid)) (layer "F.SilkS"))
    (fp_line (start -0.4 -3.327) (end 0 -2.627)
      (stroke (width 0.15) (type solid)) (layer "F.SilkS"))
    (fp_line (start 0 -2.627) (end 0.4 -3.327)
      (stroke (width 0.15) (type solid)) (layer "F.SilkS"))
    (fp_line (start 0.4 -3.327) (end -0.4 -3.327)
      (stroke (width 0.15) (type solid)) (layer "F.SilkS"))
    (fp_line (start 15.7 -2.25) (end 15.7 8.75)
      (stroke (width 0.15) (type solid)) (layer "F.SilkS"))
    (fp_line (start 15.7 8.75) (end -3.1 8.75)
      (stroke (width 0.15) (type solid)) (layer "F.SilkS"))
    (fp_circle (center 0 -3) (end 0.05 -3)
      (stroke (width 0.15) (type solid)) (fill solid) (layer "F.SilkS"))
    (fp_circle (center 0 5.5) (end 0.513 5.5)
      (stroke (width 1.0262) (type solid)) (fill none) (layer "B.Mask"))
    (fp_circle (center 4.2 0) (end 4.713 0)
      (stroke (width 1.0262) (type solid)) (fill none) (layer "B.Mask"))
    (fp_circle (center 4.2 5.5) (end 4.713 5.5)
      (stroke (width 1.0262) (type solid)) (fill none) (layer "B.Mask"))
    (fp_circle (center 8.4 0) (end 8.913 0)
      (stroke (width 1.0262) (type solid)) (fill none) (layer "B.Mask"))
    (fp_circle (center 8.4 5.5) (end 8.913 5.5)
      (stroke (width 1.0262) (type solid)) (fill none) (layer "B.Mask"))
    (fp_circle (center 12.6 0) (end 13.113 0)
      (stroke (width 1.0262) (type solid)) (fill none) (layer "B.Mask"))
    (fp_circle (center 12.6 5.5) (end 13.113 5.5)
      (stroke (width 1.0262) (type solid)) (fill none) (layer "B.Mask"))
    (fp_poly
      (pts
        (xy -1.026 -1.026)
        (xy 1.026 -1.026)
        (xy 1.026 1.026)
        (xy -1.026 1.026)
      )

      (stroke (width 0.01) (type solid)) (fill solid) (layer "B.Mask"))
    (fp_circle (center 0 5.5) (end 0.513 5.5)
      (stroke (width 1.0262) (type solid)) (fill none) (layer "F.Mask"))
    (fp_circle (center 4.2 0) (end 4.713 0)
      (stroke (width 1.0262) (type solid)) (fill none) (layer "F.Mask"))
    (fp_circle (center 4.2 5.5) (end 4.713 5.5)
      (stroke (width 1.0262) (type solid)) (fill none) (layer "F.Mask"))
    (fp_circle (center 8.4 0) (end 8.913 0)
      (stroke (width 1.0262) (type solid)) (fill none) (layer "F.Mask"))
    (fp_circle (center 8.4 5.5) (end 8.913 5.5)
      (stroke (width 1.0262) (type solid)) (fill none) (layer "F.Mask"))
    (fp_circle (center 12.6 0) (end 13.113 0)
      (stroke (width 1.0262) (type solid)) (fill none) (layer "F.Mask"))
    (fp_circle (center 12.6 5.5) (end 13.113 5.5)
      (stroke (width 1.0262) (type solid)) (fill none) (layer "F.Mask"))
    (fp_poly
      (pts
        (xy -1.026 -1.026)
        (xy 1.026 -1.026)
        (xy 1.026 1.026)
        (xy -1.026 1.026)
      )

      (stroke (width 0.01) (type solid)) (fill solid) (layer "F.Mask"))
    (fp_rect (start -3.5 -2.7) (end 16.1 9.1)
      (stroke (width 0.05) (type solid)) (fill none) (layer "F.CrtYd"))
    (fp_line (start -3.1 8.75) (end -3.1 -0.98)
      (stroke (width 0.15) (type solid)) (layer "F.Fab"))
    (fp_line (start -1.83 -2.25) (end -3.1 -0.98)
      (stroke (width 0.15) (type solid)) (layer "F.Fab"))
    (fp_line (start -1.83 -2.25) (end 15.7 -2.25)
      (stroke (width 0.15) (type solid)) (layer "F.Fab"))
    (fp_line (start -0.4 -3.327) (end 0 -2.627)
      (stroke (width 0.15) (type solid)) (layer "F.Fab"))
    (fp_line (start 0 -2.627) (end 0.4 -3.327)
      (stroke (width 0.15) (type solid)) (layer "F.Fab"))
    (fp_line (start 0.4 -3.327) (end -0.4 -3.327)
      (stroke (width 0.15) (type solid)) (layer "F.Fab"))
    (fp_line (start 15.7 -2.25) (end 15.7 8.75)
      (stroke (width 0.15) (type solid)) (layer "F.Fab"))
    (fp_line (start 15.7 8.75) (end -3.1 8.75)
      (stroke (width 0.15) (type solid)) (layer "F.Fab"))
    (pad "1" thru_hole rect (at 0 0 90) (size 1.9 1.9) (drill 1.4) (layers "*.Cu")
      (net 4 "GND") (pinfunction "1") (pintype "bidirectional"))
    (pad "2" thru_hole circle (at 4.2 0 90) (size 1.9 1.9) (drill 1.4) (layers "*.Cu")
      (net 4 "GND") (pinfunction "2") (pintype "bidirectional"))
    (pad "3" thru_hole circle (at 8.4 0 90) (size 1.9 1.9) (drill 1.4) (layers "*.Cu")
      (net 4 "GND") (pinfunction "3") (pintype "bidirectional"))
    (pad "4" thru_hole circle (at 12.6 0 90) (size 1.9 1.9) (drill 1.4) (layers "*.Cu")
      (net 4 "GND") (pinfunction "4") (pintype "bidirectional"))
    (pad "5" thru_hole circle (at 0 5.5 90) (size 1.9 1.9) (drill 1.4) (layers "*.Cu")
      (net 41 "LOAD_1") (pinfunction "5") (pintype "bidirectional"))
    (pad "6" thru_hole circle (at 4.2 5.5 90) (size 1.9 1.9) (drill 1.4) (layers "*.Cu")
      (net 41 "LOAD_1") (pinfunction "6") (pintype "bidirectional"))
    (pad "7" thru_hole circle (at 8.4 5.5 90) (size 1.9 1.9) (drill 1.4) (layers "*.Cu")
      (net 41 "LOAD_1") (pinfunction "7") (pintype "bidirectional"))
    (pad "8" thru_hole circle (at 12.6 5.5 90) (size 1.9 1.9) (drill 1.4) (layers "*.Cu")
      (net 41 "LOAD_1") (pinfunction "8") (pintype "bidirectional"))
  )
	(footprint "antmicro-footprints:MP_Pad6mm_Drill3.2mm" (layer "F.Cu")
    (at 94 53.9)
    (property "Author" "Antmicro")
    (property "License" "Apache-2.0")
    (property "Sheetfile" "d1600e-psu-breakout-board.kicad_sch")
    (property "Sheetname" "")
    (property "exclude_from_bom" "")
    (property "ki_description" "Mechanical part")
    (property "ki_keywords" "MECHANICAL")
    (attr exclude_from_pos_files exclude_from_bom)
    (fp_text reference "MP1" (at 0 -3.2) (layer "F.SilkS") hide
        (effects (font (size 0.7 0.7) (thickness 0.15)) (justify left bottom))
    )
    (fp_text value "MP_Pad6mm_Drill3.2mm" (at 0 3.9) (layer "F.Fab")
        (effects (font (size 0.7 0.7) (thickness 0.15)) (justify left bottom))
    )
    (fp_text user "${REFERENCE}" (at -0.178 6.025) (layer "F.Fab") hide
        (effects (font (size 0.7 0.7) (thickness 0.15)) (justify left bottom))
    )
    (fp_text user "Author: Antmicro" (at -0.178 7.225) (layer "F.Fab") hide
        (effects (font (size 0.7 0.7) (thickness 0.15)) (justify left bottom))
    )
    (fp_text user "License: Apache-2.0" (at -0.178 8.425) (layer "F.Fab") hide
        (effects (font (size 0.7 0.7) (thickness 0.15)) (justify left bottom))
    )
    (fp_circle (center 0 0) (end 3.25 0)
      (stroke (width 0.05) (type default)) (fill none) (layer "F.CrtYd"))
    (pad "1" thru_hole circle (at 0 0) (size 6 6) (drill 3.2) (layers "*.Cu" "*.Mask")
      (net 4 "GND") (pintype "passive"))
  )
	(footprint "antmicro-footprints:TP_SMD_1mm" (layer "F.Cu")
    (at 115.6 131.4 -90)
    (property "Author" "Antmicro")
    (property "License" "Apache-2.0")
    (property "MPN" "")
    (property "Manufacturer" "")
    (property "Sheetfile" "d1600e-psu-breakout-board.kicad_sch")
    (property "Sheetname" "")
    (property "exclude_from_bom" "")
    (property "ki_description" "Test point 1mm SMD")
    (property "ki_keywords" "TESTPOINT")
    (attr exclude_from_pos_files exclude_from_bom)
    (fp_text reference "TP_S18" (at -0.7 -0.45 -90) (layer "F.SilkS")
        (effects (font (size 0.7 0.7) (thickness 0.15)) (justify left bottom))
    )
    (fp_text value "TP_1mm_SMD" (at 0 1.4 -90) (layer "F.Fab")
        (effects (font (size 0.7 0.7) (thickness 0.15)) (justify left bottom))
    )
    (fp_text user "Author: Antmicro" (at -0.5 4 -90) (layer "F.Fab") hide
        (effects (font (size 0.7 0.7) (thickness 0.15)) (justify left bottom))
    )
    (fp_text user "${REFERENCE}" (at -0.5 2.8 -90) (layer "F.Fab") hide
        (effects (font (size 0.7 0.7) (thickness 0.15)) (justify left bottom))
    )
    (fp_text user "License: Apache-2.0" (at -0.5 5.2 -90) (layer "F.Fab") hide
        (effects (font (size 0.7 0.7) (thickness 0.15)) (justify left bottom))
    )
    (fp_circle (center 0 0) (end 0.6 0)
      (stroke (width 0.05) (type default)) (fill none) (layer "F.CrtYd"))
    (pad "1" smd circle (at 0 0 270) (size 1 1) (layers "F.Cu" "F.Mask")
      (net 73 "Net-(J10-PadS18)") (pinfunction "1") (pintype "passive"))
  )
)
